(kicad_pcb
	(version 20260206)
	(generator "pcbnew")
	(generator_version "10.0")
	(general
		(thickness 1.6)
		(legacy_teardrops no)
	)
	(paper "A4")
	(title_block
		(title "03242023_DA0F0TMBIJ0_F0T_Motherboard_J_brd_V01_OCP.brd")
		(comment 1 "Grand Teton / footprints 5234-5239 of 6105")
	)
	(layers
		(0 "F.Cu" signal "TOP")
		(4 "In1.Cu" signal "GND")
		(6 "In2.Cu" signal "IN1")
		(8 "In3.Cu" signal "GND1")
		(10 "In4.Cu" signal "IN2")
		(12 "In5.Cu" signal "GND2")
		(14 "In6.Cu" signal "IN3")
		(16 "In7.Cu" signal "GND3")
		(18 "In8.Cu" signal "VCC")
		(20 "In9.Cu" signal "VCC1")
		(22 "In10.Cu" signal "GND4")
		(24 "In11.Cu" signal "IN4")
		(26 "In12.Cu" signal "GND5")
		(28 "In13.Cu" signal "IN5")
		(30 "In14.Cu" signal "GND6")
		(32 "In15.Cu" signal "IN6")
		(34 "In16.Cu" signal "GND7")
		(2 "B.Cu" signal "BOTTOM")
		(9 "F.Adhes" user "F.Adhesive")
		(11 "B.Adhes" user "B.Adhesive")
		(13 "F.Paste" user "Package Geometry/Pastemask Top")
		(15 "B.Paste" user "Package Geometry/Pastemask Bottom")
		(5 "F.SilkS" user "Ref Des/Silkscreen Top")
		(7 "B.SilkS" user "Ref Des/Silkscreen Bottom")
		(1 "F.Mask" user "Board Geometry/Soldermask Top")
		(3 "B.Mask" user "Board Geometry/Soldermask Bottom")
		(17 "Dwgs.User" user "User.Drawings")
		(19 "Cmts.User" user "User.Comments")
		(21 "Eco1.User" user "User.Eco1")
		(23 "Eco2.User" user "User.Eco2")
		(25 "Edge.Cuts" user "Board Geometry/Outline")
		(27 "Margin" user)
		(31 "F.CrtYd" user "Package Geometry/Place Bound Top")
		(29 "B.CrtYd" user "Package Geometry/Place Bound Bottom")
		(35 "F.Fab" user "Ref Des/Assembly Top")
		(33 "B.Fab" user "Ref Des/Assembly Bottom")
	)
	(footprint ""
		(layer "B.Cu")
		(at 310.843422 -314.550044 90)
		(property "Reference" "R2498"
			(at 0 0 90)
			(layer "B.SilkS")
			(hide yes)
			(effects
				(font
					(size 1.27 1.27)
				)
				(justify mirror)
			)
		)
		(property "Value" ""
			(at 0 0 90)
			(layer "B.Fab")
			(effects
				(font
					(size 1.27 1.27)
				)
				(justify mirror)
			)
		)
		(duplicate_pad_numbers_are_jumpers no)
		(fp_line
			(start 0.7874 -0.4064)
			(end -0.7874 -0.4064)
			(stroke
				(width 0.1524)
				(type default)
			)
			(layer "B.SilkS")
		)
		(fp_line
			(start -0.7874 -0.4064)
			(end -0.7874 0.4064)
			(stroke
				(width 0.1524)
				(type default)
			)
			(layer "B.SilkS")
		)
		(fp_line
			(start 0.7874 0.4064)
			(end 0.7874 -0.4064)
			(stroke
				(width 0.1524)
				(type default)
			)
			(layer "B.SilkS")
		)
		(fp_line
			(start -0.7874 0.4064)
			(end 0.7874 0.4064)
			(stroke
				(width 0.1524)
				(type default)
			)
			(layer "B.SilkS")
		)
		(fp_line
			(start 0.67945 -0.305054)
			(end 0.12065 -0.305054)
			(stroke
				(width 0.1)
				(type default)
			)
			(layer "B.Fab")
		)
		(fp_line
			(start 0.12065 -0.305054)
			(end 0.12065 -0.2794)
			(stroke
				(width 0.1)
				(type default)
			)
			(layer "B.Fab")
		)
		(fp_line
			(start -0.12065 -0.3048)
			(end -0.67945 -0.3048)
			(stroke
				(width 0.1)
				(type default)
			)
			(layer "B.Fab")
		)
		(fp_line
			(start -0.67945 -0.3048)
			(end -0.67945 0.3048)
			(stroke
				(width 0.1)
				(type default)
			)
			(layer "B.Fab")
		)
		(fp_line
			(start 0.12065 -0.2794)
			(end -0.12065 -0.2794)
			(stroke
				(width 0.1)
				(type default)
			)
			(layer "B.Fab")
		)
		(fp_line
			(start -0.12065 -0.2794)
			(end -0.12065 -0.3048)
			(stroke
				(width 0.1)
				(type default)
			)
			(layer "B.Fab")
		)
		(fp_line
			(start 0.12065 0.2794)
			(end 0.12065 0.3048)
			(stroke
				(width 0.1)
				(type default)
			)
			(layer "B.Fab")
		)
		(fp_line
			(start -0.120396 0.2794)
			(end 0.12065 0.2794)
			(stroke
				(width 0.1)
				(type default)
			)
			(layer "B.Fab")
		)
		(fp_line
			(start 0.67945 0.3048)
			(end 0.67945 -0.305054)
			(stroke
				(width 0.1)
				(type default)
			)
			(layer "B.Fab")
		)
		(fp_line
			(start 0.12065 0.3048)
			(end 0.67945 0.3048)
			(stroke
				(width 0.1)
				(type default)
			)
			(layer "B.Fab")
		)
		(fp_line
			(start -0.120396 0.3048)
			(end -0.120396 0.2794)
			(stroke
				(width 0.1)
				(type default)
			)
			(layer "B.Fab")
		)
		(fp_line
			(start -0.67945 0.3048)
			(end -0.120396 0.3048)
			(stroke
				(width 0.1)
				(type default)
			)
			(layer "B.Fab")
		)
		(pad "1" smd circle
			(at 0.40005 0 270)
			(size 0 0)
			(layers "B.Cu" "B.Mask" "B.Paste")
			(net "PWRGD_FAIL_CPU0_AB_R1")
		)
		(pad "2" smd circle
			(at -0.40005 0 270)
			(size 0 0)
			(layers "B.Cu" "B.Mask" "B.Paste")
			(net "PWRGD_FAIL_CPU0_AB_R")
		)
	)
	(footprint ""
		(layer "B.Cu")
		(at 34.003742 -315.557662)
		(property "Reference" "R3893"
			(at 0 0 0)
			(layer "B.SilkS")
			(hide yes)
			(effects
				(font
					(size 1.27 1.27)
				)
				(justify mirror)
			)
		)
		(property "Value" ""
			(at 0 0 0)
			(layer "B.Fab")
			(effects
				(font
					(size 1.27 1.27)
				)
				(justify mirror)
			)
		)
		(duplicate_pad_numbers_are_jumpers no)
		(fp_line
			(start -0.7874 -0.4064)
			(end -0.7874 0.4064)
			(stroke
				(width 0.1524)
				(type default)
			)
			(layer "B.SilkS")
		)
		(fp_line
			(start -0.7874 0.4064)
			(end 0.7874 0.4064)
			(stroke
				(width 0.1524)
				(type default)
			)
			(layer "B.SilkS")
		)
		(fp_line
			(start 0.7874 -0.4064)
			(end -0.7874 -0.4064)
			(stroke
				(width 0.1524)
				(type default)
			)
			(layer "B.SilkS")
		)
		(fp_line
			(start 0.7874 0.4064)
			(end 0.7874 -0.4064)
			(stroke
				(width 0.1524)
				(type default)
			)
			(layer "B.SilkS")
		)
		(fp_line
			(start -0.67945 -0.3048)
			(end -0.67945 0.3048)
			(stroke
				(width 0.1)
				(type default)
			)
			(layer "B.Fab")
		)
		(fp_line
			(start -0.67945 0.3048)
			(end -0.120396 0.3048)
			(stroke
				(width 0.1)
				(type default)
			)
			(layer "B.Fab")
		)
		(fp_line
			(start -0.12065 -0.3048)
			(end -0.67945 -0.3048)
			(stroke
				(width 0.1)
				(type default)
			)
			(layer "B.Fab")
		)
		(fp_line
			(start -0.12065 -0.2794)
			(end -0.12065 -0.3048)
			(stroke
				(width 0.1)
				(type default)
			)
			(layer "B.Fab")
		)
		(fp_line
			(start -0.120396 0.2794)
			(end 0.12065 0.2794)
			(stroke
				(width 0.1)
				(type default)
			)
			(layer "B.Fab")
		)
		(fp_line
			(start -0.120396 0.3048)
			(end -0.120396 0.2794)
			(stroke
				(width 0.1)
				(type default)
			)
			(layer "B.Fab")
		)
		(fp_line
			(start 0.12065 -0.305054)
			(end 0.12065 -0.2794)
			(stroke
				(width 0.1)
				(type default)
			)
			(layer "B.Fab")
		)
		(fp_line
			(start 0.12065 -0.2794)
			(end -0.12065 -0.2794)
			(stroke
				(width 0.1)
				(type default)
			)
			(layer "B.Fab")
		)
		(fp_line
			(start 0.12065 0.2794)
			(end 0.12065 0.3048)
			(stroke
				(width 0.1)
				(type default)
			)
			(layer "B.Fab")
		)
		(fp_line
			(start 0.12065 0.3048)
			(end 0.67945 0.3048)
			(stroke
				(width 0.1)
				(type default)
			)
			(layer "B.Fab")
		)
		(fp_line
			(start 0.67945 -0.305054)
			(end 0.12065 -0.305054)
			(stroke
				(width 0.1)
				(type default)
			)
			(layer "B.Fab")
		)
		(fp_line
			(start 0.67945 0.3048)
			(end 0.67945 -0.305054)
			(stroke
				(width 0.1)
				(type default)
			)
			(layer "B.Fab")
		)
		(pad "1" smd circle
			(at 0.40005 0 180)
			(size 0 0)
			(layers "B.Cu" "B.Mask" "B.Paste")
			(net "I3C_SPD_DDRABCD_CPU1_LVC1_SCL_2")
		)
		(pad "2" smd circle
			(at -0.40005 0 180)
			(size 0 0)
			(layers "B.Cu" "B.Mask" "B.Paste")
			(net "I3C_SPD_DDRABCD_CPU1_LVC1_SCL")
		)
	)
	(footprint ""
		(layer "B.Cu")
		(at 389.636 -32.603948 90)
		(property "Reference" "R3160"
			(at 0 0 90)
			(layer "B.SilkS")
			(hide yes)
			(effects
				(font
					(size 1.27 1.27)
				)
				(justify mirror)
			)
		)
		(property "Value" ""
			(at 0 0 90)
			(layer "B.Fab")
			(effects
				(font
					(size 1.27 1.27)
				)
				(justify mirror)
			)
		)
		(duplicate_pad_numbers_are_jumpers no)
		(fp_line
			(start 0.7874 -0.4064)
			(end -0.7874 -0.4064)
			(stroke
				(width 0.1524)
				(type default)
			)
			(layer "B.SilkS")
		)
		(fp_line
			(start -0.7874 -0.4064)
			(end -0.7874 0.4064)
			(stroke
				(width 0.1524)
				(type default)
			)
			(layer "B.SilkS")
		)
		(fp_line
			(start 0.7874 0.4064)
			(end 0.7874 -0.4064)
			(stroke
				(width 0.1524)
				(type default)
			)
			(layer "B.SilkS")
		)
		(fp_line
			(start -0.7874 0.4064)
			(end 0.7874 0.4064)
			(stroke
				(width 0.1524)
				(type default)
			)
			(layer "B.SilkS")
		)
		(fp_line
			(start 0.67945 -0.305054)
			(end 0.12065 -0.305054)
			(stroke
				(width 0.1)
				(type default)
			)
			(layer "B.Fab")
		)
		(fp_line
			(start 0.12065 -0.305054)
			(end 0.12065 -0.2794)
			(stroke
				(width 0.1)
				(type default)
			)
			(layer "B.Fab")
		)
		(fp_line
			(start -0.12065 -0.3048)
			(end -0.67945 -0.3048)
			(stroke
				(width 0.1)
				(type default)
			)
			(layer "B.Fab")
		)
		(fp_line
			(start -0.67945 -0.3048)
			(end -0.67945 0.3048)
			(stroke
				(width 0.1)
				(type default)
			)
			(layer "B.Fab")
		)
		(fp_line
			(start 0.12065 -0.2794)
			(end -0.12065 -0.2794)
			(stroke
				(width 0.1)
				(type default)
			)
			(layer "B.Fab")
		)
		(fp_line
			(start -0.12065 -0.2794)
			(end -0.12065 -0.3048)
			(stroke
				(width 0.1)
				(type default)
			)
			(layer "B.Fab")
		)
		(fp_line
			(start 0.12065 0.2794)
			(end 0.12065 0.3048)
			(stroke
				(width 0.1)
				(type default)
			)
			(layer "B.Fab")
		)
		(fp_line
			(start -0.120396 0.2794)
			(end 0.12065 0.2794)
			(stroke
				(width 0.1)
				(type default)
			)
			(layer "B.Fab")
		)
		(fp_line
			(start 0.67945 0.3048)
			(end 0.67945 -0.305054)
			(stroke
				(width 0.1)
				(type default)
			)
			(layer "B.Fab")
		)
		(fp_line
			(start 0.12065 0.3048)
			(end 0.67945 0.3048)
			(stroke
				(width 0.1)
				(type default)
			)
			(layer "B.Fab")
		)
		(fp_line
			(start -0.120396 0.3048)
			(end -0.120396 0.2794)
			(stroke
				(width 0.1)
				(type default)
			)
			(layer "B.Fab")
		)
		(fp_line
			(start -0.67945 0.3048)
			(end -0.120396 0.3048)
			(stroke
				(width 0.1)
				(type default)
			)
			(layer "B.Fab")
		)
		(pad "1" smd circle
			(at 0.40005 0 270)
			(size 0 0)
			(layers "B.Cu" "B.Mask" "B.Paste")
			(net "P3V3_AUX")
		)
		(pad "2" smd circle
			(at -0.40005 0 270)
			(size 0 0)
			(layers "B.Cu" "B.Mask" "B.Paste")
			(net "HP_OCP_V3_1_RST_R")
		)
	)
	(footprint ""
		(layer "B.Cu")
		(at 185.555128 -317.40475 180)
		(property "Reference" "R2496"
			(at 0 0 0)
			(layer "B.SilkS")
			(hide yes)
			(effects
				(font
					(size 1.27 1.27)
				)
				(justify mirror)
			)
		)
		(property "Value" ""
			(at 0 0 0)
			(layer "B.Fab")
			(effects
				(font
					(size 1.27 1.27)
				)
				(justify mirror)
			)
		)
		(duplicate_pad_numbers_are_jumpers no)
		(fp_line
			(start 0.7874 0.4064)
			(end 0.7874 -0.4064)
			(stroke
				(width 0.1524)
				(type default)
			)
			(layer "B.SilkS")
		)
		(fp_line
			(start 0.7874 -0.4064)
			(end -0.7874 -0.4064)
			(stroke
				(width 0.1524)
				(type default)
			)
			(layer "B.SilkS")
		)
		(fp_line
			(start -0.7874 0.4064)
			(end 0.7874 0.4064)
			(stroke
				(width 0.1524)
				(type default)
			)
			(layer "B.SilkS")
		)
		(fp_line
			(start -0.7874 -0.4064)
			(end -0.7874 0.4064)
			(stroke
				(width 0.1524)
				(type default)
			)
			(layer "B.SilkS")
		)
		(fp_line
			(start 0.67945 0.3048)
			(end 0.67945 -0.305054)
			(stroke
				(width 0.1)
				(type default)
			)
			(layer "B.Fab")
		)
		(fp_line
			(start 0.67945 -0.305054)
			(end 0.12065 -0.305054)
			(stroke
				(width 0.1)
				(type default)
			)
			(layer "B.Fab")
		)
		(fp_line
			(start 0.12065 0.3048)
			(end 0.67945 0.3048)
			(stroke
				(width 0.1)
				(type default)
			)
			(layer "B.Fab")
		)
		(fp_line
			(start 0.12065 0.2794)
			(end 0.12065 0.3048)
			(stroke
				(width 0.1)
				(type default)
			)
			(layer "B.Fab")
		)
		(fp_line
			(start 0.12065 -0.2794)
			(end -0.12065 -0.2794)
			(stroke
				(width 0.1)
				(type default)
			)
			(layer "B.Fab")
		)
		(fp_line
			(start 0.12065 -0.305054)
			(end 0.12065 -0.2794)
			(stroke
				(width 0.1)
				(type default)
			)
			(layer "B.Fab")
		)
		(fp_line
			(start -0.120396 0.3048)
			(end -0.120396 0.2794)
			(stroke
				(width 0.1)
				(type default)
			)
			(layer "B.Fab")
		)
		(fp_line
			(start -0.120396 0.2794)
			(end 0.12065 0.2794)
			(stroke
				(width 0.1)
				(type default)
			)
			(layer "B.Fab")
		)
		(fp_line
			(start -0.12065 -0.2794)
			(end -0.12065 -0.3048)
			(stroke
				(width 0.1)
				(type default)
			)
			(layer "B.Fab")
		)
		(fp_line
			(start -0.12065 -0.3048)
			(end -0.67945 -0.3048)
			(stroke
				(width 0.1)
				(type default)
			)
			(layer "B.Fab")
		)
		(fp_line
			(start -0.67945 0.3048)
			(end -0.120396 0.3048)
			(stroke
				(width 0.1)
				(type default)
			)
			(layer "B.Fab")
		)
		(fp_line
			(start -0.67945 -0.3048)
			(end -0.67945 0.3048)
			(stroke
				(width 0.1)
				(type default)
			)
			(layer "B.Fab")
		)
		(pad "1" smd circle
			(at 0.40005 0)
			(size 0 0)
			(layers "B.Cu" "B.Mask" "B.Paste")
			(net "PWRGD_FAIL_CPU1_EF")
		)
		(pad "2" smd circle
			(at -0.40005 0)
			(size 0 0)
			(layers "B.Cu" "B.Mask" "B.Paste")
			(net "PWRGD_FAIL_CPU1_EF_R1")
		)
	)
	(footprint ""
		(layer "B.Cu")
		(at 322.984622 -58.283348 180)
		(property "Reference" "R1485"
			(at 0 0 0)
			(layer "B.SilkS")
			(hide yes)
			(effects
				(font
					(size 1.27 1.27)
				)
				(justify mirror)
			)
		)
		(property "Value" ""
			(at 0 0 0)
			(layer "B.Fab")
			(effects
				(font
					(size 1.27 1.27)
				)
				(justify mirror)
			)
		)
		(duplicate_pad_numbers_are_jumpers no)
		(fp_line
			(start 0.7874 0.4064)
			(end 0.7874 -0.4064)
			(stroke
				(width 0.1524)
				(type default)
			)
			(layer "B.SilkS")
		)
		(fp_line
			(start 0.7874 -0.4064)
			(end -0.7874 -0.4064)
			(stroke
				(width 0.1524)
				(type default)
			)
			(layer "B.SilkS")
		)
		(fp_line
			(start -0.7874 0.4064)
			(end 0.7874 0.4064)
			(stroke
				(width 0.1524)
				(type default)
			)
			(layer "B.SilkS")
		)
		(fp_line
			(start -0.7874 -0.4064)
			(end -0.7874 0.4064)
			(stroke
				(width 0.1524)
				(type default)
			)
			(layer "B.SilkS")
		)
		(fp_line
			(start 0.67945 0.3048)
			(end 0.67945 -0.305054)
			(stroke
				(width 0.1)
				(type default)
			)
			(layer "B.Fab")
		)
		(fp_line
			(start 0.67945 -0.305054)
			(end 0.12065 -0.305054)
			(stroke
				(width 0.1)
				(type default)
			)
			(layer "B.Fab")
		)
		(fp_line
			(start 0.12065 0.3048)
			(end 0.67945 0.3048)
			(stroke
				(width 0.1)
				(type default)
			)
			(layer "B.Fab")
		)
		(fp_line
			(start 0.12065 0.2794)
			(end 0.12065 0.3048)
			(stroke
				(width 0.1)
				(type default)
			)
			(layer "B.Fab")
		)
		(fp_line
			(start 0.12065 -0.2794)
			(end -0.12065 -0.2794)
			(stroke
				(width 0.1)
				(type default)
			)
			(layer "B.Fab")
		)
		(fp_line
			(start 0.12065 -0.305054)
			(end 0.12065 -0.2794)
			(stroke
				(width 0.1)
				(type default)
			)
			(layer "B.Fab")
		)
		(fp_line
			(start -0.120396 0.3048)
			(end -0.120396 0.2794)
			(stroke
				(width 0.1)
				(type default)
			)
			(layer "B.Fab")
		)
		(fp_line
			(start -0.120396 0.2794)
			(end 0.12065 0.2794)
			(stroke
				(width 0.1)
				(type default)
			)
			(layer "B.Fab")
		)
		(fp_line
			(start -0.12065 -0.2794)
			(end -0.12065 -0.3048)
			(stroke
				(width 0.1)
				(type default)
			)
			(layer "B.Fab")
		)
		(fp_line
			(start -0.12065 -0.3048)
			(end -0.67945 -0.3048)
			(stroke
				(width 0.1)
				(type default)
			)
			(layer "B.Fab")
		)
		(fp_line
			(start -0.67945 0.3048)
			(end -0.120396 0.3048)
			(stroke
				(width 0.1)
				(type default)
			)
			(layer "B.Fab")
		)
		(fp_line
			(start -0.67945 -0.3048)
			(end -0.67945 0.3048)
			(stroke
				(width 0.1)
				(type default)
			)
			(layer "B.Fab")
		)
		(pad "1" smd circle
			(at 0.40005 0)
			(size 0 0)
			(layers "B.Cu" "B.Mask" "B.Paste")
			(net "PVNN_TERM_CPU0")
		)
		(pad "2" smd circle
			(at -0.40005 0)
			(size 0 0)
			(layers "B.Cu" "B.Mask" "B.Paste")
			(net "FM_PCH_TRIGGER0_R_N")
		)
	)
	(footprint ""
		(layer "B.Cu")
		(at 326.205342 -48.358298)
		(property "Reference" "R1960"
			(at 0 0 0)
			(layer "B.SilkS")
			(hide yes)
			(effects
				(font
					(size 1.27 1.27)
				)
				(justify mirror)
			)
		)
		(property "Value" ""
			(at 0 0 0)
			(layer "B.Fab")
			(effects
				(font
					(size 1.27 1.27)
				)
				(justify mirror)
			)
		)
		(duplicate_pad_numbers_are_jumpers no)
		(fp_line
			(start -0.7874 -0.4064)
			(end -0.7874 0.4064)
			(stroke
				(width 0.1524)
				(type default)
			)
			(layer "B.SilkS")
		)
		(fp_line
			(start -0.7874 0.4064)
			(end 0.7874 0.4064)
			(stroke
				(width 0.1524)
				(type default)
			)
			(layer "B.SilkS")
		)
		(fp_line
			(start 0.7874 -0.4064)
			(end -0.7874 -0.4064)
			(stroke
				(width 0.1524)
				(type default)
			)
			(layer "B.SilkS")
		)
		(fp_line
			(start 0.7874 0.4064)
			(end 0.7874 -0.4064)
			(stroke
				(width 0.1524)
				(type default)
			)
			(layer "B.SilkS")
		)
		(fp_line
			(start -0.67945 -0.3048)
			(end -0.67945 0.3048)
			(stroke
				(width 0.1)
				(type default)
			)
			(layer "B.Fab")
		)
		(fp_line
			(start -0.67945 0.3048)
			(end -0.120396 0.3048)
			(stroke
				(width 0.1)
				(type default)
			)
			(layer "B.Fab")
		)
		(fp_line
			(start -0.12065 -0.3048)
			(end -0.67945 -0.3048)
			(stroke
				(width 0.1)
				(type default)
			)
			(layer "B.Fab")
		)
		(fp_line
			(start -0.12065 -0.2794)
			(end -0.12065 -0.3048)
			(stroke
				(width 0.1)
				(type default)
			)
			(layer "B.Fab")
		)
		(fp_line
			(start -0.120396 0.2794)
			(end 0.12065 0.2794)
			(stroke
				(width 0.1)
				(type default)
			)
			(layer "B.Fab")
		)
		(fp_line
			(start -0.120396 0.3048)
			(end -0.120396 0.2794)
			(stroke
				(width 0.1)
				(type default)
			)
			(layer "B.Fab")
		)
		(fp_line
			(start 0.12065 -0.305054)
			(end 0.12065 -0.2794)
			(stroke
				(width 0.1)
				(type default)
			)
			(layer "B.Fab")
		)
		(fp_line
			(start 0.12065 -0.2794)
			(end -0.12065 -0.2794)
			(stroke
				(width 0.1)
				(type default)
			)
			(layer "B.Fab")
		)
		(fp_line
			(start 0.12065 0.2794)
			(end 0.12065 0.3048)
			(stroke
				(width 0.1)
				(type default)
			)
			(layer "B.Fab")
		)
		(fp_line
			(start 0.12065 0.3048)
			(end 0.67945 0.3048)
			(stroke
				(width 0.1)
				(type default)
			)
			(layer "B.Fab")
		)
		(fp_line
			(start 0.67945 -0.305054)
			(end 0.12065 -0.305054)
			(stroke
				(width 0.1)
				(type default)
			)
			(layer "B.Fab")
		)
		(fp_line
			(start 0.67945 0.3048)
			(end 0.67945 -0.305054)
			(stroke
				(width 0.1)
				(type default)
			)
			(layer "B.Fab")
		)
		(pad "1" smd circle
			(at 0.40005 0 180)
			(size 0 0)
			(layers "B.Cu" "B.Mask" "B.Paste")
			(net "H_CPU0_PMSYNC_PCH_R2")
		)
		(pad "2" smd circle
			(at -0.40005 0 180)
			(size 0 0)
			(layers "B.Cu" "B.Mask" "B.Paste")
			(net "H_CPU0_PMSYNC_PCH_R")
		)
	)
)
